Created on vSure / Trilogy - Netlist Compare Summary.

Version 

FTP Site : valor.com
WEB Site : http://www.valor.com 

DATE :  11 Dec 2015
TIME :  16:29:44


     MISMATCH SUMMARY REPORT
     -----------------------

Job  : 12433-2a_200604567      Job  : 12433-2a_200604567
Step : db                      Step : db
Type : CAD                     Type : CURCAD

-----------------------------------------------

 Mismatch Type: shorted

   P12V                  -   NET00007            
   P12V_FAN6             -    "                  
   P12V_FAN2             -    "                  
   P12V_FAN3             -    "                  
   P12V_FAN5             -    "                  
   P3V3_IN               -    "                  
   P12V_FAN1             -    "                  
   P12V_FAN4             -    "                  
   P3V3                  -   NET00035            
   P3V3_LX_COPPER        -    "                  
   ADM1276_GATE          -   NET00241            
   ADM1276_GATE_DRV      -    "                  

 Total : 3
-----------------------------------------------

 Mismatch Type: broken


 Total : 0
-----------------------------------------------

 Mismatch Type: missing


 Total : 0
-----------------------------------------------

 Mismatch Type: extra


 Total : 0
-----------------------------------------------
